# BASEBOARD_FAB2 (Tioga Pass) — schematic netlist excerpt (pin names and nets, part order shuffled) for the footprints in the layout excerpt that follows; sources: Cadence DE-HDL packaged netlist, KiCad conversion of Wiwynn_Tioga_Pass_MB.brd

C4C9  CAP  1.0UF 16V 10% X6S  pkg 0402  page 205 : A = VR_FET_SW_P12V_STBY_PVCCIN_CPU0 ; B = GND
R7F35  RES  0.0 5% CHIP  pkg 0402  page 231 : A = GND ; B = AGND_PVPP_ABC
CT3  CAP  1000PF 50V 10% X7R  pkg 0402LF  page 202 : A = VR_PVCCIN_CPU0_PHASE1 ; B = VR_PVCCIN_CPU0_PHASE1_RC

(kicad_pcb
	(version 20260206)
	(generator "pcbnew")
	(generator_version "10.0")
	(general
		(thickness 1.6)
		(legacy_teardrops no)
	)
	(paper "A4")
	(title_block
		(title "Wiwynn_Tioga_Pass_MB.brd")
		(comment 1 "Tioga Pass / footprints 1550-1552 of 4770")
	)
	(layers
		(0 "F.Cu" signal "TOP")
		(4 "In1.Cu" signal "L2GND")
		(6 "In2.Cu" signal "L3")
		(8 "In3.Cu" signal "L4GND")
		(10 "In4.Cu" signal "L5")
		(12 "In5.Cu" signal "L6GND")
		(14 "In6.Cu" signal "L7VCC")
		(16 "In7.Cu" signal "L8VCC")
		(18 "In8.Cu" signal "L9GND")
		(20 "In9.Cu" signal "L10")
		(22 "In10.Cu" signal "L11GND")
		(24 "In11.Cu" signal "L12")
		(26 "In12.Cu" signal "L13GND")
		(2 "B.Cu" signal "BOTTOM")
		(9 "F.Adhes" user "F.Adhesive")
		(11 "B.Adhes" user "B.Adhesive")
		(13 "F.Paste" user "Package Geometry/Pastemask Top")
		(15 "B.Paste" user "Package Geometry/Pastemask Bottom")
		(5 "F.SilkS" user "Ref Des/Silkscreen Top")
		(7 "B.SilkS" user "Ref Des/Silkscreen Bottom")
		(1 "F.Mask" user "Board Geometry/Soldermask Top")
		(3 "B.Mask" user "Board Geometry/Soldermask Bottom")
		(17 "Dwgs.User" user "User.Drawings")
		(19 "Cmts.User" user "User.Comments")
		(21 "Eco1.User" user "User.Eco1")
		(23 "Eco2.User" user "User.Eco2")
		(25 "Edge.Cuts" user "Board Geometry/Outline")
		(27 "Margin" user)
		(31 "F.CrtYd" user "Package Geometry/Place Bound Top")
		(29 "B.CrtYd" user "Package Geometry/Place Bound Bottom")
		(35 "F.Fab" user "Ref Des/Assembly Top")
		(33 "B.Fab" user "Ref Des/Assembly Bottom")
	)
	(footprint ""
		(layer "F.Cu")
		(at 204.0509 -52.7304 -90)
		(property "Reference" "CT3"
			(at -0.8382 -0.67818 270)
			(unlocked yes)
			(layer "F.SilkS")
			(effects
				(font
					(size 0.4064 0.254)
					(thickness 0.1524)
				)
				(justify left)
			)
		)
		(property "Value" ""
			(at 0 0 270)
			(layer "F.Fab")
			(effects
				(font
					(size 1.27 1.27)
				)
			)
		)
		(duplicate_pad_numbers_are_jumpers no)
		(fp_poly
			(pts
				(xy 0.3048 -0.1016) (xy 0.3048 0.9906) (xy -0.3048 0.9906) (xy -0.3048 -0.1016)
			)
			(stroke
				(width 0)
				(type default)
			)
			(fill no)
			(layer "F.CrtYd")
		)
		(fp_line
			(start -0.3048 0.9906)
			(end 0.3048 0.9906)
			(stroke
				(width 0.1)
				(type default)
			)
			(layer "F.Fab")
		)
		(fp_line
			(start 0.3048 0.9906)
			(end 0.3048 -0.1016)
			(stroke
				(width 0.1)
				(type default)
			)
			(layer "F.Fab")
		)
		(fp_line
			(start -0.3048 -0.1016)
			(end -0.3048 0.9906)
			(stroke
				(width 0.1)
				(type default)
			)
			(layer "F.Fab")
		)
		(fp_line
			(start 0.3048 -0.1016)
			(end -0.3048 -0.1016)
			(stroke
				(width 0.1)
				(type default)
			)
			(layer "F.Fab")
		)
		(pad "1" smd rect
			(at 0 0 270)
			(size 0.508 0.508)
			(layers "F.Cu" "F.Mask" "F.Paste")
			(net "VR_PVCCIN_CPU0_PHASE1")
		)
		(pad "2" smd rect
			(at 0 0.889 270)
			(size 0.508 0.508)
			(layers "F.Cu" "F.Mask" "F.Paste")
			(net "VR_PVCCIN_CPU0_PHASE1_RC")
		)
		(zone
			(layer "F.Cu")
			(hatch none 0.5)
			(connect_pads
				(clearance 0)
			)
			(min_thickness 0.25)
			(keepout
				(tracks not_allowed)
				(vias allowed)
				(pads allowed)
				(copperpour not_allowed)
				(footprints allowed)
			)
			(placement
				(enabled no)
				(sheetname "")
			)
			(fill
				(thermal_gap 0.5)
				(thermal_bridge_width 0.5)
				(island_removal_mode 0)
			)
			(polygon
				(pts
					(xy 203.4159 -52.9844) (xy 203.4159 -52.4764) (xy 203.7969 -52.4764) (xy 203.7969 -52.9844)
				)
			)
		)
		(zone
			(layer "F.Cu")
			(hatch none 0.5)
			(connect_pads
				(clearance 0)
			)
			(min_thickness 0.25)
			(keepout
				(tracks allowed)
				(vias not_allowed)
				(pads allowed)
				(copperpour not_allowed)
				(footprints allowed)
			)
			(placement
				(enabled no)
				(sheetname "")
			)
			(fill
				(thermal_gap 0.5)
				(thermal_bridge_width 0.5)
				(island_removal_mode 0)
			)
			(polygon
				(pts
					(xy 203.7969 -52.9844) (xy 203.7969 -52.4764) (xy 203.4159 -52.4764) (xy 203.4159 -52.9844)
				)
			)
		)
	)
	(footprint ""
		(layer "F.Cu")
		(at 339.471 -21.971 90)
		(property "Reference" "R7F35"
			(at 0 0 90)
			(layer "F.SilkS")
			(hide yes)
			(effects
				(font
					(size 1.27 1.27)
				)
			)
		)
		(property "Value" ""
			(at 0 0 90)
			(layer "F.Fab")
			(effects
				(font
					(size 1.27 1.27)
				)
			)
		)
		(duplicate_pad_numbers_are_jumpers no)
		(fp_rect
			(start 0.2794 -0.1016)
			(end -0.2794 0.9906)
			(stroke
				(width 0)
				(type default)
			)
			(fill no)
			(layer "F.CrtYd")
		)
		(fp_line
			(start 0.2794 -0.1016)
			(end -0.2794 -0.1016)
			(stroke
				(width 0.1)
				(type default)
			)
			(layer "F.Fab")
		)
		(fp_line
			(start -0.2794 -0.1016)
			(end -0.2794 0.9906)
			(stroke
				(width 0.1)
				(type default)
			)
			(layer "F.Fab")
		)
		(fp_line
			(start 0.2794 0.9906)
			(end 0.2794 -0.1016)
			(stroke
				(width 0.1)
				(type default)
			)
			(layer "F.Fab")
		)
		(fp_line
			(start -0.2794 0.9906)
			(end 0.2794 0.9906)
			(stroke
				(width 0.1)
				(type default)
			)
			(layer "F.Fab")
		)
		(pad "1" smd rect
			(at 0 0 90)
			(size 0.508 0.508)
			(layers "F.Cu" "F.Mask" "F.Paste")
			(net "GND")
		)
		(pad "2" smd rect
			(at 0 0.889 90)
			(size 0.508 0.508)
			(layers "F.Cu" "F.Mask" "F.Paste")
			(net "AGND_PVPP_ABC")
		)
		(zone
			(layer "F.Cu")
			(hatch none 0.5)
			(connect_pads
				(clearance 0)
			)
			(min_thickness 0.25)
			(keepout
				(tracks not_allowed)
				(vias allowed)
				(pads allowed)
				(copperpour not_allowed)
				(footprints allowed)
			)
			(placement
				(enabled no)
				(sheetname "")
			)
			(fill
				(thermal_gap 0.5)
				(thermal_bridge_width 0.5)
				(island_removal_mode 0)
			)
			(polygon
				(pts
					(xy 339.725 -22.225) (xy 339.725 -21.717) (xy 340.106 -21.717) (xy 340.106 -22.225)
				)
			)
		)
		(zone
			(layer "F.Cu")
			(hatch none 0.5)
			(connect_pads
				(clearance 0)
			)
			(min_thickness 0.25)
			(keepout
				(tracks allowed)
				(vias not_allowed)
				(pads allowed)
				(copperpour not_allowed)
				(footprints allowed)
			)
			(placement
				(enabled no)
				(sheetname "")
			)
			(fill
				(thermal_gap 0.5)
				(thermal_bridge_width 0.5)
				(island_removal_mode 0)
			)
			(polygon
				(pts
					(xy 339.725 -22.225) (xy 339.725 -21.717) (xy 340.106 -21.717) (xy 340.106 -22.225)
				)
			)
		)
	)
	(footprint ""
		(layer "F.Cu")
		(at 198.37908 -101.221286 90)
		(property "Reference" "C4C9"
			(at 0 0 90)
			(layer "F.SilkS")
			(hide yes)
			(effects
				(font
					(size 1.27 1.27)
				)
			)
		)
		(property "Value" ""
			(at 0 0 90)
			(layer "F.Fab")
			(effects
				(font
					(size 1.27 1.27)
				)
			)
		)
		(duplicate_pad_numbers_are_jumpers no)
		(fp_poly
			(pts
				(xy 0.3048 -0.1016) (xy 0.3048 0.9906) (xy -0.3048 0.9906) (xy -0.3048 -0.1016)
			)
			(stroke
				(width 0)
				(type default)
			)
			(fill no)
			(layer "F.CrtYd")
		)
		(fp_line
			(start 0.3048 -0.1016)
			(end -0.3048 -0.1016)
			(stroke
				(width 0.1)
				(type default)
			)
			(layer "F.Fab")
		)
		(fp_line
			(start -0.3048 -0.1016)
			(end -0.3048 0.9906)
			(stroke
				(width 0.1)
				(type default)
			)
			(layer "F.Fab")
		)
		(fp_line
			(start 0.3048 0.9906)
			(end 0.3048 -0.1016)
			(stroke
				(width 0.1)
				(type default)
			)
			(layer "F.Fab")
		)
		(fp_line
			(start -0.3048 0.9906)
			(end 0.3048 0.9906)
			(stroke
				(width 0.1)
				(type default)
			)
			(layer "F.Fab")
		)
		(pad "1" smd rect
			(at 0 0 90)
			(size 0.508 0.508)
			(layers "F.Cu" "F.Mask" "F.Paste")
			(net "VR_FET_SW_P12V_STBY_PVCCIN_CPU0")
		)
		(pad "2" smd rect
			(at 0 0.889 90)
			(size 0.508 0.508)
			(layers "F.Cu" "F.Mask" "F.Paste")
			(net "GND")
		)
		(zone
			(layer "F.Cu")
			(hatch none 0.5)
			(connect_pads
				(clearance 0)
			)
			(min_thickness 0.25)
			(keepout
				(tracks allowed)
				(vias not_allowed)
				(pads allowed)
				(copperpour not_allowed)
				(footprints allowed)
			)
			(placement
				(enabled no)
				(sheetname "")
			)
			(fill
				(thermal_gap 0.5)
				(thermal_bridge_width 0.5)
				(island_removal_mode 0)
			)
			(polygon
				(pts
					(xy 198.63308 -100.967286) (xy 198.63308 -101.475286) (xy 199.01408 -101.475286) (xy 199.01408 -100.967286)
				)
			)
		)
		(zone
			(layer "F.Cu")
			(hatch none 0.5)
			(connect_pads
				(clearance 0)
			)
			(min_thickness 0.25)
			(keepout
				(tracks not_allowed)
				(vias allowed)
				(pads allowed)
				(copperpour not_allowed)
				(footprints allowed)
			)
			(placement
				(enabled no)
				(sheetname "")
			)
			(fill
				(thermal_gap 0.5)
				(thermal_bridge_width 0.5)
				(island_removal_mode 0)
			)
			(polygon
				(pts
					(xy 199.01408 -100.967286) (xy 199.01408 -101.475286) (xy 198.63308 -101.475286) (xy 198.63308 -100.967286)
				)
			)
		)
	)
)
